# S9S_MB_2U (Grand Teton) — schematic netlist excerpt (pin names and nets, part order shuffled) for the footprints in the layout excerpt that follows; sources: Cadence DE-HDL packaged netlist, KiCad conversion of 03242023_DA0F0TMBIJ0_F0T_Motherboard_J_brd_V01_OCP.brd

J21  SCONN288_ADR50017P130CC  SCONN288_ADR50017-P130CC IO  pkg DDR288S_1-1VXB  page 102
  VIN_BULK0  = P12V_S3_AUX_CPU1_NVDIMM
  RFU0  = TP_CHC_CPU1_DIMM1_FRU_0
  VIN_MGMT  = P3V3_AUX
  HSCL  = I3C_SPD_DDRABCD_CPU1_LVC1_SCL_4
  HSDA  = I3C_SPD_DDRABCD_CPU1_LVC1_SDA
  VSS0  = GND
  DQ0_A  = M_C_CPU1_SA_DQ<0>
  VSS1  = GND
  DQ1_A  = M_C_CPU1_SA_DQ<1>
  VSS2  = GND
  DQS0_A_T  = M_C_CPU1_SA_DQS_DP<0>
  DQS0_A_C  = M_C_CPU1_SA_DQS_DN<0>
  VSS3  = GND
  DQ4_A  = M_C_CPU1_SA_DQ<4>
  VSS4  = GND
  DQ5_A  = M_C_CPU1_SA_DQ<5>
  VSS5  = GND
  DQ8_A  = M_C_CPU1_SA_DQ<8>
  VSS6  = GND
  DQ9_A  = M_C_CPU1_SA_DQ<9>
  VSS7  = GND
  DQS1_A_T  = M_C_CPU1_SA_DQS_DP<1>
  DQS1_A_C  = M_C_CPU1_SA_DQS_DN<1>
  VSS8  = GND
  DQ12_A  = M_C_CPU1_SA_DQ<12>
  VSS9  = GND
  DQ13_A  = M_C_CPU1_SA_DQ<13>
  VSS10  = GND
  DQ16_A  = M_C_CPU1_SA_DQ<16>
  VSS11  = GND
  DQ17_A  = M_C_CPU1_SA_DQ<17>
  VSS12  = GND
  DQS2_A_T  = M_C_CPU1_SA_DQS_DP<2>
  DQS2_A_C  = M_C_CPU1_SA_DQS_DN<2>
  VSS13  = GND
  DQ20_A  = M_C_CPU1_SA_DQ<20>
  VSS14  = GND
  DQ21_A  = M_C_CPU1_SA_DQ<21>
  VSS15  = GND
  DQ24_A  = M_C_CPU1_SA_DQ<24>
  VSS16  = GND
  DQ25_A  = M_C_CPU1_SA_DQ<25>
  VSS17  = GND
  DQS3_A_T  = M_C_CPU1_SA_DQS_DP<3>
  DQS3_A_C  = M_C_CPU1_SA_DQS_DN<3>
  VSS18  = GND
  DQ28_A  = M_C_CPU1_SA_DQ<28>
  VSS19  = GND
  DQ29_A  = M_C_CPU1_SA_DQ<29>
  VSS20  = GND
  CB0_A  = M_C_CPU1_SA_CB<0>
  VSS21  = GND
  CB1_A  = M_C_CPU1_SA_CB<1>
  VSS22  = GND
  DQS4_A_T  = M_C_CPU1_SA_DQS_DP<4>
  DQS4_A_C  = M_C_CPU1_SA_DQS_DN<4>
  VSS23  = GND
  CB4_A  = M_C_CPU1_SA_CB<4>
  VSS24  = GND
  CB5_A  = M_C_CPU1_SA_CB<5>
  VSS25  = GND
  ALERT_N  = M_C_CPU1_ALERT_N
  VSS26  = GND
  CS0_A_N  = M_C_CPU1_SA_CS_N<0>
  VSS27  = GND
  CA0_A  = M_C_CPU1_SA_CA<0>
  VSS28  = GND
  CA2_A  = M_C_CPU1_SA_CA<2>
  VSS29  = GND
  CA4_A  = M_C_CPU1_SA_CA<4>
  VSS30  = GND
  CA6_A  = M_C_CPU1_SA_CA<6>
  VSS31  = GND
  PAR_A  = M_C_CPU1_SA_PAR
  VSS32  = GND
  CA0_B  = M_C_CPU1_SB_CA<0>
  VSS33  = GND
  CA2_B  = M_C_CPU1_SB_CA<2>
  VSS34  = GND
  CA4_B  = M_C_CPU1_SB_CA<4>
  VSS35  = GND
  CA6_B  = M_C_CPU1_SB_CA<6>
  VSS36  = GND
  CS0_B_N  = M_C_CPU1_SB_CS_N<0>
  VSS37  = GND
  \lbd||rsp_a_n\  = M_C_CPU1_SA_RSP<0>
  \lbs||rsp_b_n\  = M_C_CPU1_SB_RSP<0>
  VSS38  = GND
  CB4_B  = M_C_CPU1_SB_CB<4>
  VSS39  = GND
  CB5_B  = M_C_CPU1_SB_CB<5>
  VSS40  = GND
  \dqs9_b_t||tdqs9_b_t||dbi4_b_n\  = M_C_CPU1_SB_DQS_DP<9>
  \dqs9_b_c||tdqs9_b_c\  = M_C_CPU1_SB_DQS_DN<9>
  VSS41  = GND
  CB0_B  = M_C_CPU1_SB_CB<0>
  VSS42  = GND
  CB1_B  = M_C_CPU1_SB_CB<1>
  VSS43  = GND
  DQ0_B  = M_C_CPU1_SB_DQ<0>
  VSS44  = GND
  DQ1_B  = M_C_CPU1_SB_DQ<1>
  VSS45  = GND
  DQS0_B_T  = M_C_CPU1_SB_DQS_DP<0>
  DQS0_B_C  = M_C_CPU1_SB_DQS_DN<0>
  VSS46  = GND
  DQ4_B  = M_C_CPU1_SB_DQ<4>
  VSS47  = GND
  DQ5_B  = M_C_CPU1_SB_DQ<5>
  VSS48  = GND
  DQ8_B  = M_C_CPU1_SB_DQ<8>
  VSS49  = GND
  DQ9_B  = M_C_CPU1_SB_DQ<9>
  VSS50  = GND
  DQS1_B_T  = M_C_CPU1_SB_DQS_DP<1>
  DQS1_B_C  = M_C_CPU1_SB_DQS_DN<1>
  VSS51  = GND
  DQ12_B  = M_C_CPU1_SB_DQ<12>
  VSS52  = GND
  DQ13_B  = M_C_CPU1_SB_DQ<13>
  VSS53  = GND
  DQ16_B  = M_C_CPU1_SB_DQ<16>
  VSS54  = GND
  DQ17_B  = M_C_CPU1_SB_DQ<17>
  VSS55  = GND
  DQS2_B_T  = M_C_CPU1_SB_DQS_DP<2>
  DQS2_B_C  = M_C_CPU1_SB_DQS_DN<2>
  VSS56  = GND
  DQ20_B  = M_C_CPU1_SB_DQ<20>
  VSS57  = GND
  DQ21_B  = M_C_CPU1_SB_DQ<21>
  VSS58  = GND
  DQ24_B  = M_C_CPU1_SB_DQ<24>
  VSS59  = GND
  DQ25_B  = M_C_CPU1_SB_DQ<25>
  VSS60  = GND
  DQS3_B_T  = M_C_CPU1_SB_DQS_DP<3>
  DQS3_B_C  = M_C_CPU1_SB_DQS_DN<3>
  VSS61  = GND
  DQ28_B  = M_C_CPU1_SB_DQ<28>
  VSS62  = GND
  DQ29_B  = M_C_CPU1_SB_DQ<29>
  VSS63  = GND
  RFU1  = TP_CHC_CPU1_DIMM1_FRU_1
  VIN_BULK1  = P12V_S3_AUX_CPU1_NVDIMM
  VIN_BULK2  = P12V_S3_AUX_CPU1_NVDIMM
  \pwr_good||fail_n\  = PWRGD_CHC_CPU1_DIMM1
  HSA  = PD_CHC_CPU1_DIMM1_SAA
  RFU2  = TP_CHC_CPU1_DIMM1_FRU_2
  RFU3  = TP_CHC_CPU1_DIMM1_FRU_3
  VSS64  = GND
  DQ2_A  = M_C_CPU1_SA_DQ<2>
  VSS65  = GND
  DQ3_A  = M_C_CPU1_SA_DQ<3>
  VSS66  = GND
  \dqs5_a_c||tdqs5_a_c||dqs5_a_t||tdqs5_a_t\  = M_C_CPU1_SA_DQS_DN<5>
  \dqs5_a_t||tdqs5_a_t\  = M_C_CPU1_SA_DQS_DP<5>
  VSS67  = GND
  DQ6_A  = M_C_CPU1_SA_DQ<6>
  VSS68  = GND
  DQ7_A  = M_C_CPU1_SA_DQ<7>
  VSS69  = GND
  DQ10_A  = M_C_CPU1_SA_DQ<10>
  VSS70  = GND
  DQ11_A  = M_C_CPU1_SA_DQ<11>
  VSS71  = GND
  \dqs6_a_c||tdqs6_a_c||dqs6_a_t||tdqs6_a_t\  = M_C_CPU1_SA_DQS_DN<6>
  \dqs6_a_t||tdqs6_a_t\  = M_C_CPU1_SA_DQS_DP<6>
  VSS72  = GND
  DQ14_A  = M_C_CPU1_SA_DQ<14>
  VSS73  = GND
  DQ15_A  = M_C_CPU1_SA_DQ<15>
  VSS74  = GND
  DQ18_A  = M_C_CPU1_SA_DQ<18>
  VSS75  = GND
  DQ19_A  = M_C_CPU1_SA_DQ<19>
  VSS76  = GND
  \dqs7_a_c||tdqs7_a_c\  = M_C_CPU1_SA_DQS_DN<7>
  \dqs7_a_t||tdqs7_a_t\  = M_C_CPU1_SA_DQS_DP<7>
  VSS77  = GND
  DQ22_A  = M_C_CPU1_SA_DQ<22>
  VSS78  = GND
  DQ23_A  = M_C_CPU1_SA_DQ<23>
  VSS79  = GND
  DQ26_A  = M_C_CPU1_SA_DQ<26>
  VSS80  = GND
  DQ27_A  = M_C_CPU1_SA_DQ<27>
  VSS81  = GND
  \dqs8_a_c||tdqs8_a_c\  = M_C_CPU1_SA_DQS_DN<8>
  \dqs8_a_t||tdqs8_a_t\  = M_C_CPU1_SA_DQS_DP<8>
  VSS82  = GND
  DQ30_A  = M_C_CPU1_SA_DQ<30>
  VSS83  = GND
  DQ31_A  = M_C_CPU1_SA_DQ<31>
  VSS84  = GND
  CB2_A  = M_C_CPU1_SA_CB<2>
  VSS85  = GND
  CB3_A  = M_C_CPU1_SA_CB<3>
  VSS86  = GND
  \dqs9_a_c||tdqs9_a_c\  = M_C_CPU1_SA_DQS_DN<9>
  \dqs9_a_t||tdqs9_a_t\  = M_C_CPU1_SA_DQS_DP<9>
  VSS87  = GND
  CB6_A  = M_C_CPU1_SA_CB<6>
  VSS88  = GND
  CB7_A  = M_C_CPU1_SA_CB<7>
  VSS89  = GND
  RESET_N  = RST_M_CD_CPU1_FPGA_N
  VSS90  = GND
  CS1_A_N  = M_C_CPU1_SA_CS_N<1>
  VSS91  = GND
  CA1_A  = M_C_CPU1_SA_CA<1>
  VSS92  = GND
  CA3_A  = M_C_CPU1_SA_CA<3>
  VSS93  = GND
  CA5_A  = M_C_CPU1_SA_CA<5>
  VSS94  = GND
  CK_T  = M_C_CPU1_CLK_DP<0>
  CK_C  = M_C_CPU1_CLK_DN<0>
  VSS95  = GND
  RFU4  = TP_CHC_CPU1_DIMM1_FRU_4
  CA1_B  = M_C_CPU1_SB_CA<1>
  VSS96  = GND
  CA3_B  = M_C_CPU1_SB_CA<3>
  VSS97  = GND
  CA5_B  = M_C_CPU1_SB_CA<5>
  VSS98  = GND
  PAR_B  = M_C_CPU1_SB_PAR
  VSS99  = GND
  CS1_B_N  = M_C_CPU1_SB_CS_N<1>
  VSS100  = GND
  RFU5  = TP_CHC_CPU1_DIMM1_FRU_5
  RFU6  = TP_CHC_CPU1_DIMM1_FRU_6
  VSS101  = GND
  CB6_B  = M_C_CPU1_SB_CB<6>
  VSS102  = GND
  CB7_B  = M_C_CPU1_SB_CB<7>
  VSS103  = GND
  DQS4_B_C  = M_C_CPU1_SB_DQS_DN<4>
  DQS4_B_T  = M_C_CPU1_SB_DQS_DP<4>
  VSS104  = GND
  CB2_B  = M_C_CPU1_SB_CB<2>
  VSS105  = GND
  CB3_B  = M_C_CPU1_SB_CB<3>
  VSS106  = GND
  DQ2_B  = M_C_CPU1_SB_DQ<2>
  VSS107  = GND
  DQ3_B  = M_C_CPU1_SB_DQ<3>
  VSS108  = GND
  \dqs5_b_c||tdqs5_b_c\  = M_C_CPU1_SB_DQS_DN<5>
  \dqs5_b_t||tdqs5_b_t\  = M_C_CPU1_SB_DQS_DP<5>
  VSS109  = GND
  DQ6_B  = M_C_CPU1_SB_DQ<6>
  VSS110  = GND
  DQ7_B  = M_C_CPU1_SB_DQ<7>
  VSS111  = GND
  DQ10_B  = M_C_CPU1_SB_DQ<10>
  VSS112  = GND
  DQ11_B  = M_C_CPU1_SB_DQ<11>
  VSS113  = GND
  \dqs6_b_c||tdqs6_b_c\  = M_C_CPU1_SB_DQS_DN<6>
  \dqs6_b_t||tdqs6_b_t\  = M_C_CPU1_SB_DQS_DP<6>
  VSS114  = GND
  DQ14_B  = M_C_CPU1_SB_DQ<14>
  VSS115  = GND
  DQ15_B  = M_C_CPU1_SB_DQ<15>
  VSS116  = GND
  DQ18_B  = M_C_CPU1_SB_DQ<18>
  VSS117  = GND
  DQ19_B  = M_C_CPU1_SB_DQ<19>
  VSS118  = GND
  \dqs7_b_c||tdqs7_b_c\  = M_C_CPU1_SB_DQS_DN<7>
  \dqs7_b_t||tdqs7_b_t\  = M_C_CPU1_SB_DQS_DP<7>
  VSS119  = GND
  DQ22_B  = M_C_CPU1_SB_DQ<22>
  VSS120  = GND
  DQ23_B  = M_C_CPU1_SB_DQ<23>
  VSS121  = GND
  DQ26_B  = M_C_CPU1_SB_DQ<26>
  VSS122  = GND
  DQ27_B  = M_C_CPU1_SB_DQ<27>
  VSS123  = GND
  \dqs8_b_c||tdqs8_b_c\  = M_C_CPU1_SB_DQS_DN<8>
  \dqs8_b_t||tdqs8_b_t\  = M_C_CPU1_SB_DQS_DP<8>
  VSS124  = GND
  DQ30_B  = M_C_CPU1_SB_DQ<30>
  VSS125  = GND
  DQ31_B  = M_C_CPU1_SB_DQ<31>
  VSS126  = GND
  G1  = GND
  G2  = GND
  G3  = GND

(kicad_pcb
	(version 20260206)
	(generator "pcbnew")
	(generator_version "10.0")
	(general
		(thickness 1.6)
		(legacy_teardrops no)
	)
	(paper "A4")
	(title_block
		(title "03242023_DA0F0TMBIJ0_F0T_Motherboard_J_brd_V01_OCP.brd")
		(comment 1 "Grand Teton / footprint 663 of 6105 (J21), pads 138-182 of 291")
	)
	(layers
		(0 "F.Cu" signal "TOP")
		(4 "In1.Cu" signal "GND")
		(6 "In2.Cu" signal "IN1")
		(8 "In3.Cu" signal "GND1")
		(10 "In4.Cu" signal "IN2")
		(12 "In5.Cu" signal "GND2")
		(14 "In6.Cu" signal "IN3")
		(16 "In7.Cu" signal "GND3")
		(18 "In8.Cu" signal "VCC")
		(20 "In9.Cu" signal "VCC1")
		(22 "In10.Cu" signal "GND4")
		(24 "In11.Cu" signal "IN4")
		(26 "In12.Cu" signal "GND5")
		(28 "In13.Cu" signal "IN5")
		(30 "In14.Cu" signal "GND6")
		(32 "In15.Cu" signal "IN6")
		(34 "In16.Cu" signal "GND7")
		(2 "B.Cu" signal "BOTTOM")
		(9 "F.Adhes" user "F.Adhesive")
		(11 "B.Adhes" user "B.Adhesive")
		(13 "F.Paste" user "Package Geometry/Pastemask Top")
		(15 "B.Paste" user "Package Geometry/Pastemask Bottom")
		(5 "F.SilkS" user "Ref Des/Silkscreen Top")
		(7 "B.SilkS" user "Ref Des/Silkscreen Bottom")
		(1 "F.Mask" user "Board Geometry/Soldermask Top")
		(3 "B.Mask" user "Board Geometry/Soldermask Bottom")
		(17 "Dwgs.User" user "User.Drawings")
		(19 "Cmts.User" user "User.Comments")
		(21 "Eco1.User" user "User.Eco1")
		(23 "Eco2.User" user "User.Eco2")
		(25 "Edge.Cuts" user "Board Geometry/Outline")
		(27 "Margin" user)
		(31 "F.CrtYd" user "Package Geometry/Place Bound Top")
		(29 "B.CrtYd" user "Package Geometry/Place Bound Bottom")
		(35 "F.Fab" user "Ref Des/Assembly Top")
		(33 "B.Fab" user "Ref Des/Assembly Bottom")
	)
	(footprint ""
		(layer "F.Cu")
		(at 25.27808 -258.091686)
		(property "Reference" "J21"
			(at -0.325882 -81.821274 0)
			(unlocked yes)
			(layer "F.SilkS")
			(effects
				(font
					(size 0.7874 0.5842)
					(thickness 0.1524)
				)
				(justify left)
			)
		)
		(property "Value" ""
			(at 0 0 0)
			(layer "F.Fab")
			(effects
				(font
					(size 1.27 1.27)
				)
			)
		)
		(duplicate_pad_numbers_are_jumpers no)
		(pad "138" smd rect
			(at -2.050034 58.224928 270)
			(size 0.519938 1.4986)
			(layers "F.Cu" "F.Mask" "F.Paste")
			(net "M_C_CPU1_SB_DQS_DN<3>")
		)
		(pad "139" smd rect
			(at -2.050034 59.075066 270)
			(size 0.519938 1.4986)
			(layers "F.Cu" "F.Mask" "F.Paste")
			(net "GND")
		)
		(pad "140" smd rect
			(at -2.050034 59.92495 270)
			(size 0.519938 1.4986)
			(layers "F.Cu" "F.Mask" "F.Paste")
			(net "M_C_CPU1_SB_DQ<28>")
		)
		(pad "141" smd rect
			(at -2.050034 60.775088 270)
			(size 0.519938 1.4986)
			(layers "F.Cu" "F.Mask" "F.Paste")
			(net "GND")
		)
		(pad "142" smd rect
			(at -2.050034 61.624972 270)
			(size 0.519938 1.4986)
			(layers "F.Cu" "F.Mask" "F.Paste")
			(net "M_C_CPU1_SB_DQ<29>")
		)
		(pad "143" smd rect
			(at -2.050034 62.47511 270)
			(size 0.519938 1.4986)
			(layers "F.Cu" "F.Mask" "F.Paste")
			(net "GND")
		)
		(pad "144" smd rect
			(at -2.050034 63.324994 270)
			(size 0.519938 1.4986)
			(layers "F.Cu" "F.Mask" "F.Paste")
			(net "TP_CHC_CPU1_DIMM1_FRU_1")
		)
		(pad "145" smd rect
			(at 2.050034 -63.324994 270)
			(size 0.519938 1.4986)
			(layers "F.Cu" "F.Mask" "F.Paste")
			(net "P12V_S3_AUX_CPU1_NVDIMM")
		)
		(pad "146" smd rect
			(at 2.050034 -62.47511 270)
			(size 0.519938 1.4986)
			(layers "F.Cu" "F.Mask" "F.Paste")
			(net "P12V_S3_AUX_CPU1_NVDIMM")
		)
		(pad "147" smd rect
			(at 2.050034 -61.624972 270)
			(size 0.519938 1.4986)
			(layers "F.Cu" "F.Mask" "F.Paste")
			(net "PWRGD_CHC_CPU1_DIMM1")
		)
		(pad "148" smd rect
			(at 2.050034 -60.775088 270)
			(size 0.519938 1.4986)
			(layers "F.Cu" "F.Mask" "F.Paste")
			(net "PD_CHC_CPU1_DIMM1_SAA")
		)
		(pad "149" smd rect
			(at 2.050034 -59.92495 270)
			(size 0.519938 1.4986)
			(layers "F.Cu" "F.Mask" "F.Paste")
			(net "TP_CHC_CPU1_DIMM1_FRU_2")
		)
		(pad "150" smd rect
			(at 2.050034 -59.075066 270)
			(size 0.519938 1.4986)
			(layers "F.Cu" "F.Mask" "F.Paste")
			(net "TP_CHC_CPU1_DIMM1_FRU_3")
		)
		(pad "151" smd rect
			(at 2.050034 -58.224928 270)
			(size 0.519938 1.4986)
			(layers "F.Cu" "F.Mask" "F.Paste")
			(net "GND")
		)
		(pad "152" smd rect
			(at 2.050034 -57.375044 270)
			(size 0.519938 1.4986)
			(layers "F.Cu" "F.Mask" "F.Paste")
			(net "M_C_CPU1_SA_DQ<2>")
		)
		(pad "153" smd rect
			(at 2.050034 -56.524906 270)
			(size 0.519938 1.4986)
			(layers "F.Cu" "F.Mask" "F.Paste")
			(net "GND")
		)
		(pad "154" smd rect
			(at 2.050034 -55.675022 270)
			(size 0.519938 1.4986)
			(layers "F.Cu" "F.Mask" "F.Paste")
			(net "M_C_CPU1_SA_DQ<3>")
		)
		(pad "155" smd rect
			(at 2.050034 -54.824884 270)
			(size 0.519938 1.4986)
			(layers "F.Cu" "F.Mask" "F.Paste")
			(net "GND")
		)
		(pad "156" smd rect
			(at 2.050034 -53.975 270)
			(size 0.519938 1.4986)
			(layers "F.Cu" "F.Mask" "F.Paste")
			(net "M_C_CPU1_SA_DQS_DN<5>")
		)
		(pad "157" smd rect
			(at 2.050034 -53.125116 270)
			(size 0.519938 1.4986)
			(layers "F.Cu" "F.Mask" "F.Paste")
			(net "M_C_CPU1_SA_DQS_DP<5>")
		)
		(pad "158" smd rect
			(at 2.050034 -52.274978 270)
			(size 0.519938 1.4986)
			(layers "F.Cu" "F.Mask" "F.Paste")
			(net "GND")
		)
		(pad "159" smd rect
			(at 2.050034 -51.425094 270)
			(size 0.519938 1.4986)
			(layers "F.Cu" "F.Mask" "F.Paste")
			(net "M_C_CPU1_SA_DQ<6>")
		)
		(pad "160" smd rect
			(at 2.050034 -50.574956 270)
			(size 0.519938 1.4986)
			(layers "F.Cu" "F.Mask" "F.Paste")
			(net "GND")
		)
		(pad "161" smd rect
			(at 2.050034 -49.725072 270)
			(size 0.519938 1.4986)
			(layers "F.Cu" "F.Mask" "F.Paste")
			(net "M_C_CPU1_SA_DQ<7>")
		)
		(pad "162" smd rect
			(at 2.050034 -48.874934 270)
			(size 0.519938 1.4986)
			(layers "F.Cu" "F.Mask" "F.Paste")
			(net "GND")
		)
		(pad "163" smd rect
			(at 2.050034 -48.02505 270)
			(size 0.519938 1.4986)
			(layers "F.Cu" "F.Mask" "F.Paste")
			(net "M_C_CPU1_SA_DQ<10>")
		)
		(pad "164" smd rect
			(at 2.050034 -47.174912 270)
			(size 0.519938 1.4986)
			(layers "F.Cu" "F.Mask" "F.Paste")
			(net "GND")
		)
		(pad "165" smd rect
			(at 2.050034 -46.325028 270)
			(size 0.519938 1.4986)
			(layers "F.Cu" "F.Mask" "F.Paste")
			(net "M_C_CPU1_SA_DQ<11>")
		)
		(pad "166" smd rect
			(at 2.050034 -45.47489 270)
			(size 0.519938 1.4986)
			(layers "F.Cu" "F.Mask" "F.Paste")
			(net "GND")
		)
		(pad "167" smd rect
			(at 2.050034 -44.625006 270)
			(size 0.519938 1.4986)
			(layers "F.Cu" "F.Mask" "F.Paste")
			(net "M_C_CPU1_SA_DQS_DN<6>")
		)
		(pad "168" smd rect
			(at 2.050034 -43.775122 270)
			(size 0.519938 1.4986)
			(layers "F.Cu" "F.Mask" "F.Paste")
			(net "M_C_CPU1_SA_DQS_DP<6>")
		)
		(pad "169" smd rect
			(at 2.050034 -42.924984 270)
			(size 0.519938 1.4986)
			(layers "F.Cu" "F.Mask" "F.Paste")
			(net "GND")
		)
		(pad "170" smd rect
			(at 2.050034 -42.0751 270)
			(size 0.519938 1.4986)
			(layers "F.Cu" "F.Mask" "F.Paste")
			(net "M_C_CPU1_SA_DQ<14>")
		)
		(pad "171" smd rect
			(at 2.050034 -41.224962 270)
			(size 0.519938 1.4986)
			(layers "F.Cu" "F.Mask" "F.Paste")
			(net "GND")
		)
		(pad "172" smd rect
			(at 2.050034 -40.375078 270)
			(size 0.519938 1.4986)
			(layers "F.Cu" "F.Mask" "F.Paste")
			(net "M_C_CPU1_SA_DQ<15>")
		)
		(pad "173" smd rect
			(at 2.050034 -39.52494 270)
			(size 0.519938 1.4986)
			(layers "F.Cu" "F.Mask" "F.Paste")
			(net "GND")
		)
		(pad "174" smd rect
			(at 2.050034 -38.675056 270)
			(size 0.519938 1.4986)
			(layers "F.Cu" "F.Mask" "F.Paste")
			(net "M_C_CPU1_SA_DQ<18>")
		)
		(pad "175" smd rect
			(at 2.050034 -37.824918 270)
			(size 0.519938 1.4986)
			(layers "F.Cu" "F.Mask" "F.Paste")
			(net "GND")
		)
		(pad "176" smd rect
			(at 2.050034 -36.975034 270)
			(size 0.519938 1.4986)
			(layers "F.Cu" "F.Mask" "F.Paste")
			(net "M_C_CPU1_SA_DQ<19>")
		)
		(pad "177" smd rect
			(at 2.050034 -36.124896 270)
			(size 0.519938 1.4986)
			(layers "F.Cu" "F.Mask" "F.Paste")
			(net "GND")
		)
		(pad "178" smd rect
			(at 2.050034 -35.275012 270)
			(size 0.519938 1.4986)
			(layers "F.Cu" "F.Mask" "F.Paste")
			(net "M_C_CPU1_SA_DQS_DN<7>")
		)
		(pad "179" smd rect
			(at 2.050034 -34.425128 270)
			(size 0.519938 1.4986)
			(layers "F.Cu" "F.Mask" "F.Paste")
			(net "M_C_CPU1_SA_DQS_DP<7>")
		)
		(pad "180" smd rect
			(at 2.050034 -33.57499 270)
			(size 0.519938 1.4986)
			(layers "F.Cu" "F.Mask" "F.Paste")
			(net "GND")
		)
		(pad "181" smd rect
			(at 2.050034 -32.725106 270)
			(size 0.519938 1.4986)
			(layers "F.Cu" "F.Mask" "F.Paste")
			(net "M_C_CPU1_SA_DQ<22>")
		)
		(pad "182" smd rect
			(at 2.050034 -31.874968 270)
			(size 0.519938 1.4986)
			(layers "F.Cu" "F.Mask" "F.Paste")
			(net "GND")
		)
	)
)
